# S9S_MB_2U (Grand Teton) — schematic netlist excerpt (pin names and nets, part order shuffled) for the footprints in the layout excerpt that follows; sources: Cadence DE-HDL packaged netlist, KiCad conversion of 03242023_DA0F0TMBIJ0_F0T_Motherboard_J_brd_V01_OCP.brd

U338  LM4040AIM3X25NOPB  LM4040AIM3X-2.5/NOPB EMPTY  pkg SOT23_123_2-92X1-3  page 307
  \1+\  = UV_P2V5_COMP
  \2-\  = GND
  \3\  = NC

U252  74LVC2G17GW  IC  pkg SOT363  page 149
  A0  = RST_PERST_SWB_R_N
  GND  = GND
  A1  = RST_PERST_SWB_R_N
  B1  = RST_PERST_1_SWB_BUF_R_N
  VCC  = P3V3_AUX
  B0  = RST_PERST_0_SWB_BUF_R_N

(kicad_pcb
	(version 20260206)
	(generator "pcbnew")
	(generator_version "10.0")
	(general
		(thickness 1.6)
		(legacy_teardrops no)
	)
	(paper "A4")
	(title_block
		(title "03242023_DA0F0TMBIJ0_F0T_Motherboard_J_brd_V01_OCP.brd")
		(comment 1 "Grand Teton / footprints 1117-1118 of 6105")
	)
	(layers
		(0 "F.Cu" signal "TOP")
		(4 "In1.Cu" signal "GND")
		(6 "In2.Cu" signal "IN1")
		(8 "In3.Cu" signal "GND1")
		(10 "In4.Cu" signal "IN2")
		(12 "In5.Cu" signal "GND2")
		(14 "In6.Cu" signal "IN3")
		(16 "In7.Cu" signal "GND3")
		(18 "In8.Cu" signal "VCC")
		(20 "In9.Cu" signal "VCC1")
		(22 "In10.Cu" signal "GND4")
		(24 "In11.Cu" signal "IN4")
		(26 "In12.Cu" signal "GND5")
		(28 "In13.Cu" signal "IN5")
		(30 "In14.Cu" signal "GND6")
		(32 "In15.Cu" signal "IN6")
		(34 "In16.Cu" signal "GND7")
		(2 "B.Cu" signal "BOTTOM")
		(9 "F.Adhes" user "F.Adhesive")
		(11 "B.Adhes" user "B.Adhesive")
		(13 "F.Paste" user "Package Geometry/Pastemask Top")
		(15 "B.Paste" user "Package Geometry/Pastemask Bottom")
		(5 "F.SilkS" user "Ref Des/Silkscreen Top")
		(7 "B.SilkS" user "Ref Des/Silkscreen Bottom")
		(1 "F.Mask" user "Board Geometry/Soldermask Top")
		(3 "B.Mask" user "Board Geometry/Soldermask Bottom")
		(17 "Dwgs.User" user "User.Drawings")
		(19 "Cmts.User" user "User.Comments")
		(21 "Eco1.User" user "User.Eco1")
		(23 "Eco2.User" user "User.Eco2")
		(25 "Edge.Cuts" user "Board Geometry/Outline")
		(27 "Margin" user)
		(31 "F.CrtYd" user "Package Geometry/Place Bound Top")
		(29 "B.CrtYd" user "Package Geometry/Place Bound Bottom")
		(35 "F.Fab" user "Ref Des/Assembly Top")
		(33 "B.Fab" user "Ref Des/Assembly Bottom")
	)
	(footprint ""
		(layer "F.Cu")
		(at 26.97988 -428.081948)
		(property "Reference" "U252"
			(at -2.56286 1.98247 0)
			(unlocked yes)
			(layer "F.SilkS")
			(effects
				(font
					(size 0.7874 0.5842)
					(thickness 0.1524)
				)
				(justify left)
			)
		)
		(property "Value" ""
			(at 0 0 0)
			(layer "F.Fab")
			(effects
				(font
					(size 1.27 1.27)
				)
			)
		)
		(duplicate_pad_numbers_are_jumpers no)
		(fp_line
			(start -1.3462 -1.100074)
			(end -0.670052 -1.100074)
			(stroke
				(width 0.1524)
				(type default)
			)
			(layer "F.SilkS")
		)
		(fp_line
			(start -1.3462 1.100074)
			(end -1.3462 -1.100074)
			(stroke
				(width 0.1524)
				(type default)
			)
			(layer "F.SilkS")
		)
		(fp_line
			(start -0.670052 -1.100074)
			(end 0 -0.381)
			(stroke
				(width 0.1524)
				(type default)
			)
			(layer "F.SilkS")
		)
		(fp_line
			(start 0 -0.381)
			(end 0.670052 -1.100074)
			(stroke
				(width 0.1524)
				(type default)
			)
			(layer "F.SilkS")
		)
		(fp_line
			(start 0.670052 -1.100074)
			(end 1.3462 -1.100074)
			(stroke
				(width 0.1524)
				(type default)
			)
			(layer "F.SilkS")
		)
		(fp_line
			(start 1.3462 -1.100074)
			(end 1.3462 1.100074)
			(stroke
				(width 0.1524)
				(type default)
			)
			(layer "F.SilkS")
		)
		(fp_line
			(start 1.3462 1.100074)
			(end -1.3462 1.100074)
			(stroke
				(width 0.1524)
				(type default)
			)
			(layer "F.SilkS")
		)
		(fp_poly
			(pts
				(xy -2.0574 -0.634746) (xy -2.8194 -0.253746) (xy -2.8194 -1.015746)
			)
			(stroke
				(width 0)
				(type default)
			)
			(fill yes)
			(layer "F.SilkS")
		)
		(fp_line
			(start -1.100074 -0.8001)
			(end -0.670052 -0.8001)
			(stroke
				(width 0.1)
				(type default)
			)
			(layer "F.Fab")
		)
		(fp_line
			(start -1.100074 0.8001)
			(end -1.100074 -0.8001)
			(stroke
				(width 0.1)
				(type default)
			)
			(layer "F.Fab")
		)
		(fp_line
			(start -0.670052 -1.100074)
			(end 0.670052 -1.100074)
			(stroke
				(width 0.1)
				(type default)
			)
			(layer "F.Fab")
		)
		(fp_line
			(start -0.670052 -0.8001)
			(end -0.670052 -1.100074)
			(stroke
				(width 0.1)
				(type default)
			)
			(layer "F.Fab")
		)
		(fp_line
			(start -0.670052 0.8001)
			(end -1.100074 0.8001)
			(stroke
				(width 0.1)
				(type default)
			)
			(layer "F.Fab")
		)
		(fp_line
			(start -0.670052 0.8001)
			(end -0.670052 -0.8001)
			(stroke
				(width 0.1)
				(type default)
			)
			(layer "F.Fab")
		)
		(fp_line
			(start -0.670052 1.100074)
			(end -0.670052 0.8001)
			(stroke
				(width 0.1)
				(type default)
			)
			(layer "F.Fab")
		)
		(fp_line
			(start 0.670052 -1.100074)
			(end 0.670052 -0.8001)
			(stroke
				(width 0.1)
				(type default)
			)
			(layer "F.Fab")
		)
		(fp_line
			(start 0.670052 -0.8001)
			(end 0.670052 0.8001)
			(stroke
				(width 0.1)
				(type default)
			)
			(layer "F.Fab")
		)
		(fp_line
			(start 0.670052 -0.8001)
			(end 1.100074 -0.8001)
			(stroke
				(width 0.1)
				(type default)
			)
			(layer "F.Fab")
		)
		(fp_line
			(start 0.670052 0.8001)
			(end 0.670052 1.100074)
			(stroke
				(width 0.1)
				(type default)
			)
			(layer "F.Fab")
		)
		(fp_line
			(start 0.670052 1.100074)
			(end -0.670052 1.100074)
			(stroke
				(width 0.1)
				(type default)
			)
			(layer "F.Fab")
		)
		(fp_line
			(start 1.100074 -0.8001)
			(end 1.100074 0.8001)
			(stroke
				(width 0.1)
				(type default)
			)
			(layer "F.Fab")
		)
		(fp_line
			(start 1.100074 0.8001)
			(end 0.670052 0.8001)
			(stroke
				(width 0.1)
				(type default)
			)
			(layer "F.Fab")
		)
		(fp_poly
			(pts
				(xy -1.524 -0.649986) (xy -2.286 -1.030986) (xy -2.286 -0.268986)
			)
			(stroke
				(width 0)
				(type default)
			)
			(fill yes)
			(layer "F.Fab")
		)
		(pad "1" smd rect
			(at -0.94996 -0.649986 270)
			(size 0.4064 0.508)
			(layers "F.Cu" "F.Mask" "F.Paste")
			(net "RST_PERST_SWB_R_N")
		)
		(pad "2" smd rect
			(at -0.94996 0 270)
			(size 0.4064 0.508)
			(layers "F.Cu" "F.Mask" "F.Paste")
			(net "GND")
		)
		(pad "3" smd rect
			(at -0.94996 0.649986 270)
			(size 0.4064 0.508)
			(layers "F.Cu" "F.Mask" "F.Paste")
			(net "RST_PERST_SWB_R_N")
		)
		(pad "4" smd rect
			(at 0.94996 0.649986 270)
			(size 0.4064 0.508)
			(layers "F.Cu" "F.Mask" "F.Paste")
			(net "RST_PERST_1_SWB_BUF_R_N")
		)
		(pad "5" smd rect
			(at 0.94996 0 270)
			(size 0.4064 0.508)
			(layers "F.Cu" "F.Mask" "F.Paste")
			(net "P3V3_AUX")
		)
		(pad "6" smd rect
			(at 0.94996 -0.649986 270)
			(size 0.4064 0.508)
			(layers "F.Cu" "F.Mask" "F.Paste")
			(net "RST_PERST_0_SWB_BUF_R_N")
		)
	)
	(footprint ""
		(layer "F.Cu")
		(at 209.4992 -111.4298 -90)
		(property "Reference" "U338"
			(at -4.24053 1.8542 0)
			(unlocked yes)
			(layer "F.SilkS")
			(effects
				(font
					(size 0.7874 0.5842)
					(thickness 0.1524)
				)
				(justify left)
			)
		)
		(property "Value" ""
			(at 0 0 270)
			(layer "F.Fab")
			(effects
				(font
					(size 1.27 1.27)
				)
			)
		)
		(duplicate_pad_numbers_are_jumpers no)
		(fp_line
			(start -1.868424 1.519936)
			(end 1.868424 1.519936)
			(stroke
				(width 0.1524)
				(type default)
			)
			(layer "F.SilkS")
		)
		(fp_line
			(start 1.868424 1.519936)
			(end 1.868424 -1.519936)
			(stroke
				(width 0.1524)
				(type default)
			)
			(layer "F.SilkS")
		)
		(fp_line
			(start -1.868424 -1.519936)
			(end -1.868424 1.519936)
			(stroke
				(width 0.1524)
				(type default)
			)
			(layer "F.SilkS")
		)
		(fp_line
			(start 1.868424 -1.519936)
			(end -1.868424 -1.519936)
			(stroke
				(width 0.1524)
				(type default)
			)
			(layer "F.SilkS")
		)
		(fp_line
			(start -0.700024 1.519936)
			(end 0.700024 1.519936)
			(stroke
				(width 0.1)
				(type default)
			)
			(layer "F.Fab")
		)
		(fp_line
			(start 0.700024 1.519936)
			(end 0.700024 -1.519936)
			(stroke
				(width 0.1)
				(type default)
			)
			(layer "F.Fab")
		)
		(fp_line
			(start -0.700024 -1.519936)
			(end -0.700024 1.519936)
			(stroke
				(width 0.1)
				(type default)
			)
			(layer "F.Fab")
		)
		(fp_line
			(start 0.700024 -1.519936)
			(end -0.700024 -1.519936)
			(stroke
				(width 0.1)
				(type default)
			)
			(layer "F.Fab")
		)
		(pad "1" smd rect
			(at -1.18491 -0.94996 180)
			(size 0.6096 1.0668)
			(layers "F.Cu" "F.Mask" "F.Paste")
			(net "UV_P2V5_COMP")
		)
		(pad "2" smd rect
			(at -1.18491 0.94996 180)
			(size 0.6096 1.0668)
			(layers "F.Cu" "F.Mask" "F.Paste")
			(net "GND")
		)
		(pad "3" smd rect
			(at 1.18491 0 180)
			(size 0.6096 1.0668)
			(layers "F.Cu" "F.Mask" "F.Paste")
			(net "Net_8627")
		)
	)
)
